FILE_TYPE = MULTI_PHYS_TABLE;
PART 'NPN_DUAL'
{========================================================================================}
:VALUE    | PACK_TYPE | MATERIAL | PART_NUMBER     = EnvComp | PART_NUMBER  | JEDEC_TYPE      | DESCRIPTION                  | HEIGHT    | COMPONENT_TYPE | LEAD_LENGTH | CLASS| LPID   | SPEED_URL | Status |RPL| AML | Bus_Unit | Days ;
{========================================================================================}
'MBT3904' | 'SSOPLF'  | 'XSTR'   | 'C52264-001'(!) = 'YES;YES;YES;UNK;ok;VLD' | 'C52264-001' | 'SSOP6_53_65MA' | 'DUAL PURPOSE TRANSISTOR LF' | '.044 IN' | 'SMALLSMT'     | ''          | 'IC' | '' | 'http://speed.intel.com:8081/speed/module/pdm/item/pdm_item_detail_direct.asp?item_cde=C52264-001&item_rev=01&url_param=unused' | 'Approved' | 'YES' | '2' | 'SMO_IC' | '56' 
'MBT3904' | 'SSOPLF'  | 'EMPTY'  | 'C52264-001'(!) = 'YES;YES;YES;UNK;ok;VLD' | 'C52264-001' | 'SSOP6_53_65MA' | 'DUAL PURPOSE TRANSISTOR LF' | '.044 IN' | 'SMALLSMT'     | ''          | 'IO' | '' | 'http://speed.intel.com:8081/speed/module/pdm/item/pdm_item_detail_direct.asp?item_cde=C52264-001&item_rev=01&url_param=unused' | 'Approved' | 'YES' | '2' | 'SMO_IC' | '56' 
END_PART
END.
